#ISCELL
  pure_quanta quanta_title_block_c *
  *
#ISCELL
  standard offpage *
  page399_i1
#ISCELL
  pure_quanta_power p1v0 *
  page399_i10
#CELL
  pure_quanta q_cap *
  page399_i11
#ISCELL
  pure_quanta_power universal_gnd *
  page399_i12
#CELL
  pure_quanta q_res *
  page399_i13
#ISCELL
  pure_quanta_power universal_gnd *
  page399_i14
#ISCELL
  pure_quanta_power universal_gnd *
  page399_i15
#ISCELL
  standard offpage *
  page399_i2
#CELL
  pure_quanta q_res *
  page399_i3
#CELL
  pure_quanta q_res *
  page399_i4
#CELL
  pure_quanta m24m02drmn6tp *
  page399_i5
#ISCELL
  pure_quanta_power universal_gnd *
  page399_i9
